(kicad_pcb
	(version 20260206)
	(generator "pcbnew")
	(generator_version "10.0")
	(general
		(thickness 1.6)
		(legacy_teardrops no)
	)
	(paper "A4")
	(title_block
		(title "Wiwynn_Tioga_Pass_MB.brd")
		(comment 1 "Tioga Pass / footprints 3609-3615 of 4770")
	)
	(layers
		(0 "F.Cu" signal "TOP")
		(4 "In1.Cu" signal "L2GND")
		(6 "In2.Cu" signal "L3")
		(8 "In3.Cu" signal "L4GND")
		(10 "In4.Cu" signal "L5")
		(12 "In5.Cu" signal "L6GND")
		(14 "In6.Cu" signal "L7VCC")
		(16 "In7.Cu" signal "L8VCC")
		(18 "In8.Cu" signal "L9GND")
		(20 "In9.Cu" signal "L10")
		(22 "In10.Cu" signal "L11GND")
		(24 "In11.Cu" signal "L12")
		(26 "In12.Cu" signal "L13GND")
		(2 "B.Cu" signal "BOTTOM")
		(9 "F.Adhes" user "F.Adhesive")
		(11 "B.Adhes" user "B.Adhesive")
		(13 "F.Paste" user "Package Geometry/Pastemask Top")
		(15 "B.Paste" user "Package Geometry/Pastemask Bottom")
		(5 "F.SilkS" user "Ref Des/Silkscreen Top")
		(7 "B.SilkS" user "Ref Des/Silkscreen Bottom")
		(1 "F.Mask" user "Board Geometry/Soldermask Top")
		(3 "B.Mask" user "Board Geometry/Soldermask Bottom")
		(17 "Dwgs.User" user "User.Drawings")
		(19 "Cmts.User" user "User.Comments")
		(21 "Eco1.User" user "User.Eco1")
		(23 "Eco2.User" user "User.Eco2")
		(25 "Edge.Cuts" user "Board Geometry/Outline")
		(27 "Margin" user)
		(31 "F.CrtYd" user "Package Geometry/Place Bound Top")
		(29 "B.CrtYd" user "Package Geometry/Place Bound Bottom")
		(35 "F.Fab" user "Ref Des/Assembly Top")
		(33 "B.Fab" user "Ref Des/Assembly Bottom")
	)
	(footprint ""
		(layer "B.Cu")
		(at 390.93775 -107.85475 90)
		(property "Reference" "C2N11"
			(at 0 0 90)
			(layer "B.SilkS")
			(hide yes)
			(effects
				(font
					(size 1.27 1.27)
				)
				(justify mirror)
			)
		)
		(property "Value" ""
			(at 0 0 90)
			(layer "B.Fab")
			(effects
				(font
					(size 1.27 1.27)
				)
				(justify mirror)
			)
		)
		(duplicate_pad_numbers_are_jumpers no)
		(fp_rect
			(start 0.2794 0.9144)
			(end -0.2794 -0.1143)
			(stroke
				(width 0)
				(type default)
			)
			(fill no)
			(layer "B.CrtYd")
		)
		(fp_line
			(start 0.2794 -0.1143)
			(end -0.2794 -0.1143)
			(stroke
				(width 0.1)
				(type default)
			)
			(layer "B.Fab")
		)
		(fp_line
			(start -0.2794 -0.1143)
			(end -0.2794 0.9144)
			(stroke
				(width 0.1)
				(type default)
			)
			(layer "B.Fab")
		)
		(fp_line
			(start 0.2794 0.9144)
			(end 0.2794 -0.1143)
			(stroke
				(width 0.1)
				(type default)
			)
			(layer "B.Fab")
		)
		(fp_line
			(start -0.2794 0.9144)
			(end 0.2794 0.9144)
			(stroke
				(width 0.1)
				(type default)
			)
			(layer "B.Fab")
		)
		(pad "1" smd custom
			(at 0 0)
			(size 0.10414 0.10414)
			(layers "B.Cu" "B.Mask" "B.Paste")
			(net "PVNN_PCH_STBY")
			(options
				(clearance outline)
				(anchor circle)
			)
			(primitives
				(gr_poly
					(pts
						(xy -0.20828 -0.08636) (xy -0.20828 0.08636) (xy -0.08636 0.20828) (xy 0.086614 0.20828) (xy 0.20828 0.086614)
						(xy 0.20828 -0.08636) (xy 0.08636 -0.20828) (xy -0.08636 -0.20828)
					)
					(width 0)
					(fill yes)
				)
			)
		)
		(pad "2" smd custom
			(at 0 0.8001)
			(size 0.10414 0.10414)
			(layers "B.Cu" "B.Mask" "B.Paste")
			(net "GND")
			(options
				(clearance outline)
				(anchor circle)
			)
			(primitives
				(gr_poly
					(pts
						(xy -0.20828 -0.08636) (xy -0.20828 0.08636) (xy -0.08636 0.20828) (xy 0.086614 0.20828) (xy 0.20828 0.086614)
						(xy 0.20828 -0.08636) (xy 0.08636 -0.20828) (xy -0.08636 -0.20828)
					)
					(width 0)
					(fill yes)
				)
			)
		)
		(zone
			(layer "B.Cu")
			(hatch none 0.5)
			(connect_pads
				(clearance 0)
			)
			(min_thickness 0.25)
			(keepout
				(tracks allowed)
				(vias not_allowed)
				(pads allowed)
				(copperpour not_allowed)
				(footprints allowed)
			)
			(placement
				(enabled no)
				(sheetname "")
			)
			(fill
				(thermal_gap 0.5)
				(thermal_bridge_width 0.5)
				(island_removal_mode 0)
			)
			(polygon
				(pts
					(xy 391.1473 -107.94238) (xy 391.5283 -107.94238) (xy 391.5283 -107.76712) (xy 391.1473 -107.766866)
				)
			)
		)
		(zone
			(layer "B.Cu")
			(hatch none 0.5)
			(connect_pads
				(clearance 0)
			)
			(min_thickness 0.25)
			(keepout
				(tracks not_allowed)
				(vias allowed)
				(pads allowed)
				(copperpour not_allowed)
				(footprints allowed)
			)
			(placement
				(enabled no)
				(sheetname "")
			)
			(fill
				(thermal_gap 0.5)
				(thermal_bridge_width 0.5)
				(island_removal_mode 0)
			)
			(polygon
				(pts
					(xy 391.1473 -107.94238) (xy 391.5283 -107.94238) (xy 391.5283 -107.76712) (xy 391.1473 -107.766866)
				)
			)
		)
	)
	(footprint ""
		(layer "B.Cu")
		(at 27.785568 -154.559 180)
		(property "Reference" "R9L3"
			(at 0 0 0)
			(layer "B.SilkS")
			(hide yes)
			(effects
				(font
					(size 1.27 1.27)
				)
				(justify mirror)
			)
		)
		(property "Value" ""
			(at 0 0 0)
			(layer "B.Fab")
			(effects
				(font
					(size 1.27 1.27)
				)
				(justify mirror)
			)
		)
		(duplicate_pad_numbers_are_jumpers no)
		(fp_poly
			(pts
				(xy 0.2794 -0.1016) (xy -0.2794 -0.1016) (xy -0.2794 0.9906) (xy 0.2794 0.9906)
			)
			(stroke
				(width 0)
				(type default)
			)
			(fill no)
			(layer "B.CrtYd")
		)
		(fp_line
			(start 0.2794 0.9906)
			(end -0.2794 0.9906)
			(stroke
				(width 0.1)
				(type default)
			)
			(layer "B.Fab")
		)
		(fp_line
			(start 0.2794 -0.1016)
			(end 0.2794 0.9906)
			(stroke
				(width 0.1)
				(type default)
			)
			(layer "B.Fab")
		)
		(fp_line
			(start -0.2794 0.9906)
			(end -0.2794 -0.1016)
			(stroke
				(width 0.1)
				(type default)
			)
			(layer "B.Fab")
		)
		(fp_line
			(start -0.2794 -0.1016)
			(end 0.2794 -0.1016)
			(stroke
				(width 0.1)
				(type default)
			)
			(layer "B.Fab")
		)
		(pad "1" smd rect
			(at 0 0)
			(size 0.508 0.508)
			(layers "B.Cu" "B.Mask" "B.Paste")
			(net "M_M_CPU_VREF")
		)
		(pad "2" smd rect
			(at 0 0.889)
			(size 0.508 0.508)
			(layers "B.Cu" "B.Mask" "B.Paste")
			(net "M_M_VREF")
		)
		(zone
			(layer "B.Cu")
			(hatch none 0.5)
			(connect_pads
				(clearance 0)
			)
			(min_thickness 0.25)
			(keepout
				(tracks not_allowed)
				(vias allowed)
				(pads allowed)
				(copperpour not_allowed)
				(footprints allowed)
			)
			(placement
				(enabled no)
				(sheetname "")
			)
			(fill
				(thermal_gap 0.5)
				(thermal_bridge_width 0.5)
				(island_removal_mode 0)
			)
			(polygon
				(pts
					(xy 27.531568 -155.194) (xy 28.039568 -155.194) (xy 28.039568 -154.813) (xy 27.531568 -154.813)
				)
			)
		)
		(zone
			(layer "B.Cu")
			(hatch none 0.5)
			(connect_pads
				(clearance 0)
			)
			(min_thickness 0.25)
			(keepout
				(tracks allowed)
				(vias not_allowed)
				(pads allowed)
				(copperpour not_allowed)
				(footprints allowed)
			)
			(placement
				(enabled no)
				(sheetname "")
			)
			(fill
				(thermal_gap 0.5)
				(thermal_bridge_width 0.5)
				(island_removal_mode 0)
			)
			(polygon
				(pts
					(xy 27.531568 -154.813) (xy 28.039568 -154.813) (xy 28.039568 -155.194) (xy 27.531568 -155.194)
				)
			)
		)
	)
	(footprint ""
		(layer "B.Cu")
		(at 495.676174 -40.573706)
		(property "Reference" "U25W7"
			(at 0 0 0)
			(layer "B.SilkS")
			(hide yes)
			(effects
				(font
					(size 1.27 1.27)
				)
				(justify mirror)
			)
		)
		(property "Value" "*"
			(at 0 -10.7315 0)
			(unlocked yes)
			(layer "B.Fab")
			(hide yes)
			(effects
				(font
					(size 1.27 1.016)
					(thickness 0.1524)
				)
				(justify mirror)
			)
		)
		(property "Device Type" "U74AHCT1G125G-AL5-R-GP-U_TTL-GA"
			(at 0 -12.2555 0)
			(unlocked yes)
			(layer "B.Fab")
			(hide yes)
			(effects
				(font
					(size 1.27 1.016)
					(thickness 0.1524)
				)
				(justify mirror)
			)
		)
		(duplicate_pad_numbers_are_jumpers no)
		(fp_line
			(start -1.24714 -1.79832)
			(end -1.24714 1.82372)
			(stroke
				(width 0.1524)
				(type default)
			)
			(layer "B.SilkS")
		)
		(fp_line
			(start -1.2446 1.81102)
			(end -1.25476 1.82118)
			(stroke
				(width 0.1524)
				(type default)
			)
			(layer "B.SilkS")
		)
		(fp_line
			(start -1.08712 -1.80848)
			(end 1.23952 -1.80848)
			(stroke
				(width 0.1524)
				(type default)
			)
			(layer "B.SilkS")
		)
		(fp_line
			(start -1.08204 -1.80848)
			(end -1.26492 -1.80848)
			(stroke
				(width 0.1524)
				(type default)
			)
			(layer "B.SilkS")
		)
		(fp_line
			(start -1.08204 1.81102)
			(end 1.4859 1.81102)
			(stroke
				(width 0.1524)
				(type default)
			)
			(layer "B.SilkS")
		)
		(fp_line
			(start -1.06934 1.81102)
			(end -1.2446 1.81102)
			(stroke
				(width 0.1524)
				(type default)
			)
			(layer "B.SilkS")
		)
		(fp_line
			(start 1.2446 1.8034)
			(end 1.2446 -1.8161)
			(stroke
				(width 0.1524)
				(type default)
			)
			(layer "B.SilkS")
		)
		(fp_line
			(start 1.3081 0.49022)
			(end 1.3081 1.7907)
			(stroke
				(width 0.508)
				(type default)
			)
			(layer "B.SilkS")
		)
		(fp_poly
			(pts
				(xy 0.82804 0.10922) (xy -0.82804 0.10922) (xy -0.82804 -0.10795) (xy 0.82804 -0.10795)
			)
			(stroke
				(width 0)
				(type default)
			)
			(fill yes)
			(layer "B.SilkS")
		)
		(fp_poly
			(pts
				(xy 1.5621 2.0447) (xy -1.5621 2.0447) (xy -1.5621 -2.0447) (xy 1.5621 -2.0447)
			)
			(stroke
				(width 0)
				(type default)
			)
			(fill no)
			(layer "B.CrtYd")
		)
		(fp_poly
			(pts
				(xy 1.5621 -2.0447) (xy -1.5621 -2.0447) (xy -1.5621 2.0447) (xy 1.5621 2.0447)
			)
			(stroke
				(width 0)
				(type default)
			)
			(fill no)
			(layer "B.Fab")
		)
		(pad "1" smd rect
			(at 0.65024 0.92202 180)
			(size 0.3556 1.2192)
			(layers "B.Cu" "B.Mask" "B.Paste")
			(net "GND")
		)
		(pad "2" smd rect
			(at 0 0.92202 180)
			(size 0.3556 1.2192)
			(layers "B.Cu" "B.Mask" "B.Paste")
			(net "BMC_VGA_HSYNC")
		)
		(pad "3" smd rect
			(at -0.65024 0.92202 180)
			(size 0.3556 1.2192)
			(layers "B.Cu" "B.Mask" "B.Paste")
			(net "GND")
		)
		(pad "4" smd rect
			(at -0.65024 -0.92075 180)
			(size 0.3556 1.2192)
			(layers "B.Cu" "B.Mask" "B.Paste")
			(net "VGA_REAR_HSYNC_S")
		)
		(pad "5" smd rect
			(at 0.65024 -0.92075 180)
			(size 0.3556 1.2192)
			(layers "B.Cu" "B.Mask" "B.Paste")
			(net "P5V_VGA_D")
		)
	)
	(footprint ""
		(layer "B.Cu")
		(at 323.8627 -31.967678 -90)
		(property "Reference" "R4T5"
			(at 0 0 90)
			(layer "B.SilkS")
			(hide yes)
			(effects
				(font
					(size 1.27 1.27)
				)
				(justify mirror)
			)
		)
		(property "Value" ""
			(at 0 0 90)
			(layer "B.Fab")
			(effects
				(font
					(size 1.27 1.27)
				)
				(justify mirror)
			)
		)
		(duplicate_pad_numbers_are_jumpers no)
		(fp_poly
			(pts
				(xy 0.2794 -0.1016) (xy -0.2794 -0.1016) (xy -0.2794 0.9906) (xy 0.2794 0.9906)
			)
			(stroke
				(width 0)
				(type default)
			)
			(fill no)
			(layer "B.CrtYd")
		)
		(fp_line
			(start -0.2794 0.9906)
			(end -0.2794 -0.1016)
			(stroke
				(width 0.1)
				(type default)
			)
			(layer "B.Fab")
		)
		(fp_line
			(start 0.2794 0.9906)
			(end -0.2794 0.9906)
			(stroke
				(width 0.1)
				(type default)
			)
			(layer "B.Fab")
		)
		(fp_line
			(start -0.2794 -0.1016)
			(end 0.2794 -0.1016)
			(stroke
				(width 0.1)
				(type default)
			)
			(layer "B.Fab")
		)
		(fp_line
			(start 0.2794 -0.1016)
			(end 0.2794 0.9906)
			(stroke
				(width 0.1)
				(type default)
			)
			(layer "B.Fab")
		)
		(pad "1" smd rect
			(at 0 0 90)
			(size 0.508 0.508)
			(layers "B.Cu" "B.Mask" "B.Paste")
			(net "PVCCIO_CPU0")
		)
		(pad "2" smd rect
			(at 0 0.889 90)
			(size 0.508 0.508)
			(layers "B.Cu" "B.Mask" "B.Paste")
			(net "SMB_DDR_ABC_SCL_G")
		)
		(zone
			(layer "B.Cu")
			(hatch none 0.5)
			(connect_pads
				(clearance 0)
			)
			(min_thickness 0.25)
			(keepout
				(tracks not_allowed)
				(vias allowed)
				(pads allowed)
				(copperpour not_allowed)
				(footprints allowed)
			)
			(placement
				(enabled no)
				(sheetname "")
			)
			(fill
				(thermal_gap 0.5)
				(thermal_bridge_width 0.5)
				(island_removal_mode 0)
			)
			(polygon
				(pts
					(xy 323.2277 -31.713678) (xy 323.2277 -32.221678) (xy 323.6087 -32.221678) (xy 323.6087 -31.713678)
				)
			)
		)
		(zone
			(layer "B.Cu")
			(hatch none 0.5)
			(connect_pads
				(clearance 0)
			)
			(min_thickness 0.25)
			(keepout
				(tracks allowed)
				(vias not_allowed)
				(pads allowed)
				(copperpour not_allowed)
				(footprints allowed)
			)
			(placement
				(enabled no)
				(sheetname "")
			)
			(fill
				(thermal_gap 0.5)
				(thermal_bridge_width 0.5)
				(island_removal_mode 0)
			)
			(polygon
				(pts
					(xy 323.6087 -31.713678) (xy 323.6087 -32.221678) (xy 323.2277 -32.221678) (xy 323.2277 -31.713678)
				)
			)
		)
	)
	(footprint ""
		(layer "B.Cu")
		(at 63.0428 -93.1672 90)
		(property "Reference" "R8N1"
			(at 0 0 90)
			(layer "B.SilkS")
			(hide yes)
			(effects
				(font
					(size 1.27 1.27)
				)
				(justify mirror)
			)
		)
		(property "Value" ""
			(at 0 0 90)
			(layer "B.Fab")
			(effects
				(font
					(size 1.27 1.27)
				)
				(justify mirror)
			)
		)
		(duplicate_pad_numbers_are_jumpers no)
		(fp_poly
			(pts
				(xy 0.2794 -0.1016) (xy -0.2794 -0.1016) (xy -0.2794 0.9906) (xy 0.2794 0.9906)
			)
			(stroke
				(width 0)
				(type default)
			)
			(fill no)
			(layer "B.CrtYd")
		)
		(fp_line
			(start 0.2794 -0.1016)
			(end 0.2794 0.9906)
			(stroke
				(width 0.1)
				(type default)
			)
			(layer "B.Fab")
		)
		(fp_line
			(start -0.2794 -0.1016)
			(end 0.2794 -0.1016)
			(stroke
				(width 0.1)
				(type default)
			)
			(layer "B.Fab")
		)
		(fp_line
			(start 0.2794 0.9906)
			(end -0.2794 0.9906)
			(stroke
				(width 0.1)
				(type default)
			)
			(layer "B.Fab")
		)
		(fp_line
			(start -0.2794 0.9906)
			(end -0.2794 -0.1016)
			(stroke
				(width 0.1)
				(type default)
			)
			(layer "B.Fab")
		)
		(pad "1" smd rect
			(at 0 0 270)
			(size 0.508 0.508)
			(layers "B.Cu" "B.Mask" "B.Paste")
			(net "P3V3_STBY")
		)
		(pad "2" smd rect
			(at 0 0.889 270)
			(size 0.508 0.508)
			(layers "B.Cu" "B.Mask" "B.Paste")
			(net "FM_CPU1_PROC_ID1")
		)
		(zone
			(layer "B.Cu")
			(hatch none 0.5)
			(connect_pads
				(clearance 0)
			)
			(min_thickness 0.25)
			(keepout
				(tracks allowed)
				(vias not_allowed)
				(pads allowed)
				(copperpour not_allowed)
				(footprints allowed)
			)
			(placement
				(enabled no)
				(sheetname "")
			)
			(fill
				(thermal_gap 0.5)
				(thermal_bridge_width 0.5)
				(island_removal_mode 0)
			)
			(polygon
				(pts
					(xy 63.2968 -93.4212) (xy 63.2968 -92.9132) (xy 63.6778 -92.9132) (xy 63.6778 -93.4212)
				)
			)
		)
		(zone
			(layer "B.Cu")
			(hatch none 0.5)
			(connect_pads
				(clearance 0)
			)
			(min_thickness 0.25)
			(keepout
				(tracks not_allowed)
				(vias allowed)
				(pads allowed)
				(copperpour not_allowed)
				(footprints allowed)
			)
			(placement
				(enabled no)
				(sheetname "")
			)
			(fill
				(thermal_gap 0.5)
				(thermal_bridge_width 0.5)
				(island_removal_mode 0)
			)
			(polygon
				(pts
					(xy 63.6778 -93.4212) (xy 63.6778 -92.9132) (xy 63.2968 -92.9132) (xy 63.2968 -93.4212)
				)
			)
		)
	)
	(footprint ""
		(layer "B.Cu")
		(at 413.734504 -48.445674 90)
		(property "Reference" "C25W46"
			(at -1.47828 0.78994 180)
			(unlocked yes)
			(layer "B.SilkS")
			(effects
				(font
					(size 0.4064 0.254)
					(thickness 0.1524)
				)
				(justify mirror)
			)
		)
		(property "Value" ""
			(at 0 0 90)
			(layer "B.Fab")
			(effects
				(font
					(size 1.27 1.27)
				)
				(justify mirror)
			)
		)
		(duplicate_pad_numbers_are_jumpers no)
		(fp_poly
			(pts
				(xy 0.7239 -0.2159) (xy -0.7239 -0.2159) (xy -0.7239 1.9939) (xy 0.7239 1.9939)
			)
			(stroke
				(width 0)
				(type default)
			)
			(fill no)
			(layer "B.CrtYd")
		)
		(fp_line
			(start 0.7239 -0.2159)
			(end 0.7239 1.9939)
			(stroke
				(width 0.1)
				(type default)
			)
			(layer "B.Fab")
		)
		(fp_line
			(start -0.7239 -0.2159)
			(end 0.7239 -0.2159)
			(stroke
				(width 0.1)
				(type default)
			)
			(layer "B.Fab")
		)
		(fp_line
			(start 0.7239 1.9939)
			(end -0.7239 1.9939)
			(stroke
				(width 0.1)
				(type default)
			)
			(layer "B.Fab")
		)
		(fp_line
			(start -0.7239 1.9939)
			(end -0.7239 -0.2159)
			(stroke
				(width 0.1)
				(type default)
			)
			(layer "B.Fab")
		)
		(pad "1" smd rect
			(at 0 0 270)
			(size 1.27 1.016)
			(layers "B.Cu" "B.Mask" "B.Paste")
			(net "VCC_D_3V3")
		)
		(pad "2" smd rect
			(at 0 1.778 270)
			(size 1.27 1.016)
			(layers "B.Cu" "B.Mask" "B.Paste")
			(net "GND")
		)
		(zone
			(layer "B.Cu")
			(hatch none 0.5)
			(connect_pads
				(clearance 0)
			)
			(min_thickness 0.25)
			(keepout
				(tracks not_allowed)
				(vias allowed)
				(pads allowed)
				(copperpour not_allowed)
				(footprints allowed)
			)
			(placement
				(enabled no)
				(sheetname "")
			)
			(fill
				(thermal_gap 0.5)
				(thermal_bridge_width 0.5)
				(island_removal_mode 0)
			)
			(polygon
				(pts
					(xy 414.242504 -49.080674) (xy 414.242504 -47.810674) (xy 415.004504 -47.810674) (xy 415.004504 -49.080674)
				)
			)
		)
	)
	(footprint ""
		(layer "B.Cu")
		(at 266.397232 -3.3528 90)
		(property "Reference" "C5G55"
			(at -1.14681 0.76708 180)
			(unlocked yes)
			(layer "B.SilkS")
			(effects
				(font
					(size 0.7874 0.5842)
					(thickness 0.1524)
				)
				(justify mirror)
			)
		)
		(property "Value" ""
			(at 0 0 90)
			(layer "B.Fab")
			(effects
				(font
					(size 1.27 1.27)
				)
				(justify mirror)
			)
		)
		(duplicate_pad_numbers_are_jumpers no)
		(fp_rect
			(start -0.4953 -0.2032)
			(end 0.4953 1.6002)
			(stroke
				(width 0)
				(type default)
			)
			(fill no)
			(layer "B.CrtYd")
		)
		(fp_line
			(start 0.4953 -0.2032)
			(end -0.4953 -0.2032)
			(stroke
				(width 0.1)
				(type default)
			)
			(layer "B.Fab")
		)
		(fp_line
			(start -0.4953 -0.2032)
			(end -0.4953 1.6002)
			(stroke
				(width 0.1)
				(type default)
			)
			(layer "B.Fab")
		)
		(fp_line
			(start 0.4953 1.6002)
			(end 0.4953 -0.2032)
			(stroke
				(width 0.1)
				(type default)
			)
			(layer "B.Fab")
		)
		(fp_line
			(start -0.4953 1.6002)
			(end 0.4953 1.6002)
			(stroke
				(width 0.1)
				(type default)
			)
			(layer "B.Fab")
		)
		(pad "1" smd rect
			(at 0 0 270)
			(size 0.762 0.889)
			(layers "B.Cu" "B.Mask" "B.Paste")
			(net "PVDDQ_ABC")
		)
		(pad "2" smd rect
			(at 0 1.397 270)
			(size 0.762 0.889)
			(layers "B.Cu" "B.Mask" "B.Paste")
			(net "GND")
		)
		(zone
			(layer "B.Cu")
			(hatch none 0.5)
			(connect_pads
				(clearance 0)
			)
			(min_thickness 0.25)
			(keepout
				(tracks not_allowed)
				(vias allowed)
				(pads allowed)
				(copperpour not_allowed)
				(footprints allowed)
			)
			(placement
				(enabled no)
				(sheetname "")
			)
			(fill
				(thermal_gap 0.5)
				(thermal_bridge_width 0.5)
				(island_removal_mode 0)
			)
			(polygon
				(pts
					(xy 266.841732 -2.9718) (xy 267.349732 -2.9718) (xy 267.349732 -3.7338) (xy 266.841732 -3.7338)
				)
			)
		)
	)
)
